# T6G (Grand Teton) — schematic netlist excerpt (pin names and nets, part order shuffled) for the footprints in the layout excerpt that follows; sources: Cadence DE-HDL packaged netlist, KiCad conversion of 04192023_DAF0TMB3IC0_F0TG_MB_C_brd_V02_OCP.brd

R2221  Q_RES  26.7K 1% EMPTY  pkg 0402LF  page 268 : A = P12V_AUX ; B = A_P12V_STBY_FP_TRIGGER
PR3843  Q_RES  49.9 1% CHIP  pkg 0603LF  page 135 : A = P12V_AUX ; B = P12V_OCP_AVIN_PD_1

(kicad_pcb
	(version 20260206)
	(generator "pcbnew")
	(generator_version "10.0")
	(general
		(thickness 1.6)
		(legacy_teardrops no)
	)
	(paper "A4")
	(title_block
		(title "04192023_DAF0TMB3IC0_F0TG_MB_C_brd_V02_OCP.brd")
		(comment 1 "Grand Teton / footprints 4808-4809 of 8354")
	)
	(layers
		(0 "F.Cu" signal "TOP")
		(4 "In1.Cu" signal "GND")
		(6 "In2.Cu" signal "IN1")
		(8 "In3.Cu" signal "GND1")
		(10 "In4.Cu" signal "IN2")
		(12 "In5.Cu" signal "GND2")
		(14 "In6.Cu" signal "IN3")
		(16 "In7.Cu" signal "GND3")
		(18 "In8.Cu" signal "VCC")
		(20 "In9.Cu" signal "VCC1")
		(22 "In10.Cu" signal "GND4")
		(24 "In11.Cu" signal "IN4")
		(26 "In12.Cu" signal "GND5")
		(28 "In13.Cu" signal "IN5")
		(30 "In14.Cu" signal "GND6")
		(32 "In15.Cu" signal "IN6")
		(34 "In16.Cu" signal "GND7")
		(2 "B.Cu" signal "BOTTOM")
		(9 "F.Adhes" user "F.Adhesive")
		(11 "B.Adhes" user "B.Adhesive")
		(13 "F.Paste" user "Package Geometry/Pastemask Top")
		(15 "B.Paste" user "Package Geometry/Pastemask Bottom")
		(5 "F.SilkS" user "Ref Des/Silkscreen Top")
		(7 "B.SilkS" user "Ref Des/Silkscreen Bottom")
		(1 "F.Mask" user "Board Geometry/Soldermask Top")
		(3 "B.Mask" user "Board Geometry/Soldermask Bottom")
		(17 "Dwgs.User" user "User.Drawings")
		(19 "Cmts.User" user "User.Comments")
		(21 "Eco1.User" user "User.Eco1")
		(23 "Eco2.User" user "User.Eco2")
		(25 "Edge.Cuts" user "Board Geometry/Outline")
		(27 "Margin" user)
		(31 "F.CrtYd" user "Package Geometry/Place Bound Top")
		(29 "B.CrtYd" user "Package Geometry/Place Bound Bottom")
		(35 "F.Fab" user "Ref Des/Assembly Top")
		(33 "B.Fab" user "Ref Des/Assembly Bottom")
	)
	(footprint ""
		(layer "F.Cu")
		(at 150.368762 -119.098822)
		(property "Reference" "R2221"
			(at 0 0 0)
			(layer "F.SilkS")
			(hide yes)
			(effects
				(font
					(size 1.27 1.27)
				)
			)
		)
		(property "Value" ""
			(at 0 0 0)
			(layer "F.Fab")
			(effects
				(font
					(size 1.27 1.27)
				)
			)
		)
		(duplicate_pad_numbers_are_jumpers no)
		(fp_line
			(start -0.7874 -0.4064)
			(end 0.7874 -0.4064)
			(stroke
				(width 0.1524)
				(type default)
			)
			(layer "F.SilkS")
		)
		(fp_line
			(start -0.7874 0.4064)
			(end -0.7874 -0.4064)
			(stroke
				(width 0.1524)
				(type default)
			)
			(layer "F.SilkS")
		)
		(fp_line
			(start 0.7874 -0.4064)
			(end 0.7874 0.4064)
			(stroke
				(width 0.1524)
				(type default)
			)
			(layer "F.SilkS")
		)
		(fp_line
			(start 0.7874 0.4064)
			(end -0.7874 0.4064)
			(stroke
				(width 0.1524)
				(type default)
			)
			(layer "F.SilkS")
		)
		(fp_line
			(start -0.67945 -0.305054)
			(end -0.12065 -0.305054)
			(stroke
				(width 0.1)
				(type default)
			)
			(layer "F.Fab")
		)
		(fp_line
			(start -0.67945 0.3048)
			(end -0.67945 -0.305054)
			(stroke
				(width 0.1)
				(type default)
			)
			(layer "F.Fab")
		)
		(fp_line
			(start -0.12065 -0.305054)
			(end -0.12065 -0.2794)
			(stroke
				(width 0.1)
				(type default)
			)
			(layer "F.Fab")
		)
		(fp_line
			(start -0.12065 -0.2794)
			(end 0.12065 -0.2794)
			(stroke
				(width 0.1)
				(type default)
			)
			(layer "F.Fab")
		)
		(fp_line
			(start -0.12065 0.2794)
			(end -0.12065 0.3048)
			(stroke
				(width 0.1)
				(type default)
			)
			(layer "F.Fab")
		)
		(fp_line
			(start -0.12065 0.3048)
			(end -0.67945 0.3048)
			(stroke
				(width 0.1)
				(type default)
			)
			(layer "F.Fab")
		)
		(fp_line
			(start 0.120396 0.2794)
			(end -0.12065 0.2794)
			(stroke
				(width 0.1)
				(type default)
			)
			(layer "F.Fab")
		)
		(fp_line
			(start 0.120396 0.3048)
			(end 0.120396 0.2794)
			(stroke
				(width 0.1)
				(type default)
			)
			(layer "F.Fab")
		)
		(fp_line
			(start 0.12065 -0.3048)
			(end 0.67945 -0.3048)
			(stroke
				(width 0.1)
				(type default)
			)
			(layer "F.Fab")
		)
		(fp_line
			(start 0.12065 -0.2794)
			(end 0.12065 -0.3048)
			(stroke
				(width 0.1)
				(type default)
			)
			(layer "F.Fab")
		)
		(fp_line
			(start 0.67945 -0.3048)
			(end 0.67945 0.3048)
			(stroke
				(width 0.1)
				(type default)
			)
			(layer "F.Fab")
		)
		(fp_line
			(start 0.67945 0.3048)
			(end 0.120396 0.3048)
			(stroke
				(width 0.1)
				(type default)
			)
			(layer "F.Fab")
		)
		(pad "1" smd circle
			(at -0.40005 0)
			(size 0 0)
			(layers "F.Cu" "F.Mask" "F.Paste")
			(net "P12V_AUX")
		)
		(pad "2" smd circle
			(at 0.40005 0)
			(size 0 0)
			(layers "F.Cu" "F.Mask" "F.Paste")
			(net "A_P12V_STBY_FP_TRIGGER")
		)
	)
	(footprint ""
		(layer "F.Cu")
		(at 439.295032 -24.009858)
		(property "Reference" "PR3843"
			(at 0 0 0)
			(layer "F.SilkS")
			(hide yes)
			(effects
				(font
					(size 1.27 1.27)
				)
			)
		)
		(property "Value" ""
			(at 0 0 0)
			(layer "F.Fab")
			(effects
				(font
					(size 1.27 1.27)
				)
			)
		)
		(duplicate_pad_numbers_are_jumpers no)
		(fp_line
			(start -1.2954 -0.5842)
			(end 1.2954 -0.5842)
			(stroke
				(width 0.1524)
				(type default)
			)
			(layer "F.SilkS")
		)
		(fp_line
			(start -1.2954 0.5842)
			(end -1.2954 -0.5842)
			(stroke
				(width 0.1524)
				(type default)
			)
			(layer "F.SilkS")
		)
		(fp_line
			(start 1.2954 -0.5842)
			(end 1.2954 0.5842)
			(stroke
				(width 0.1524)
				(type default)
			)
			(layer "F.SilkS")
		)
		(fp_line
			(start 1.2954 0.5842)
			(end -1.2954 0.5842)
			(stroke
				(width 0.1524)
				(type default)
			)
			(layer "F.SilkS")
		)
		(fp_line
			(start -1.1938 -0.406654)
			(end -0.8636 -0.406654)
			(stroke
				(width 0.1)
				(type default)
			)
			(layer "F.Fab")
		)
		(fp_line
			(start -1.1938 0.4064)
			(end -1.1938 -0.406654)
			(stroke
				(width 0.1)
				(type default)
			)
			(layer "F.Fab")
		)
		(fp_line
			(start -0.8636 -0.4572)
			(end 0.8636 -0.4572)
			(stroke
				(width 0.1)
				(type default)
			)
			(layer "F.Fab")
		)
		(fp_line
			(start -0.8636 -0.406654)
			(end -0.8636 -0.4572)
			(stroke
				(width 0.1)
				(type default)
			)
			(layer "F.Fab")
		)
		(fp_line
			(start -0.8636 0.4064)
			(end -1.1938 0.4064)
			(stroke
				(width 0.1)
				(type default)
			)
			(layer "F.Fab")
		)
		(fp_line
			(start -0.8636 0.4318)
			(end -0.8636 0.4064)
			(stroke
				(width 0.1)
				(type default)
			)
			(layer "F.Fab")
		)
		(fp_line
			(start -0.8636 0.4572)
			(end -0.8636 0.4318)
			(stroke
				(width 0.1)
				(type default)
			)
			(layer "F.Fab")
		)
		(fp_line
			(start 0.8636 -0.4572)
			(end 0.8636 -0.406654)
			(stroke
				(width 0.1)
				(type default)
			)
			(layer "F.Fab")
		)
		(fp_line
			(start 0.8636 -0.406654)
			(end 1.1938 -0.406654)
			(stroke
				(width 0.1)
				(type default)
			)
			(layer "F.Fab")
		)
		(fp_line
			(start 0.8636 0.4064)
			(end 0.8636 0.4572)
			(stroke
				(width 0.1)
				(type default)
			)
			(layer "F.Fab")
		)
		(fp_line
			(start 0.8636 0.4572)
			(end -0.8636 0.4572)
			(stroke
				(width 0.1)
				(type default)
			)
			(layer "F.Fab")
		)
		(fp_line
			(start 1.1938 -0.406654)
			(end 1.1938 0.4064)
			(stroke
				(width 0.1)
				(type default)
			)
			(layer "F.Fab")
		)
		(fp_line
			(start 1.1938 0.4064)
			(end 0.8636 0.4064)
			(stroke
				(width 0.1)
				(type default)
			)
			(layer "F.Fab")
		)
		(pad "1" smd rect
			(at -0.7366 0 270)
			(size 0.7112 0.8128)
			(layers "F.Cu" "F.Mask" "F.Paste")
			(net "P12V_AUX")
		)
		(pad "2" smd rect
			(at 0.7366 0 270)
			(size 0.7112 0.8128)
			(layers "F.Cu" "F.Mask" "F.Paste")
			(net "P12V_OCP_AVIN_PD_1")
		)
	)
)
